# Barreleye-G2_Tri-mode Expander-DVT-X01-SKU-BOM-X07-20171222_Final.xls.xlsx — TBD AVL Qual (bom)
| NOTES: |  |  |  |  |  |  |
| The following items are alternates to the items listed in the Critical Components Qual tab. |  |  |  |  |  |  |
| These components will be included on near future, non-customer builds for validation and approval by both Customer and the ODM. |  |  |  |  |  |  |
| Item Description | ODM P/N | Customer PN | Vendor | Vendor PN | Build ?? | Estimated Completion Date |
| SATA connectors (black) |  |  |  |  |  |  |
| -  Alternate |  |  |  |  |  |  |
| SATA connectors (blue) |  |  |  |  |  |  |
| -  Alternate |  |  |  |  |  |  |
| PCIe retention |  |  |  |  |  |  |
| -  Alternate |  |  |  |  |  |  |
| RTC XTAL |  |  |  |  |  |  |
| -  Alternate |  |  |  |  |  |  |
| XTAL |  |  |  |  |  |  |
| -  Alternate |  |  |  |  |  |  |
